(kicad_pcb
	(version 20260206)
	(generator "pcbnew")
	(generator_version "10.0")
	(general
		(thickness 1.6)
		(legacy_teardrops no)
	)
	(paper "A4")
	(title_block
		(title "panther-plus-userver — 13130-1b_20150205.brd")
		(comment 1 "Honey Badger (Wiwynn) / footprint 406 of 1509 (DIMM2), pads 156-162 of 210")
	)
	(layers
		(0 "F.Cu" signal "TOP")
		(4 "In1.Cu" signal "L2")
		(6 "In2.Cu" signal "L3")
		(8 "In3.Cu" signal "L4")
		(10 "In4.Cu" signal "L5")
		(12 "In5.Cu" signal "L6")
		(14 "In6.Cu" signal "L7")
		(16 "In7.Cu" signal "L8")
		(18 "In8.Cu" signal "L9")
		(20 "In9.Cu" signal "L10")
		(22 "In10.Cu" signal "L11")
		(2 "B.Cu" signal "BOTTOM")
		(9 "F.Adhes" user "F.Adhesive")
		(11 "B.Adhes" user "B.Adhesive")
		(13 "F.Paste" user "Package Geometry/Pastemask Top")
		(15 "B.Paste" user "Package Geometry/Pastemask Bottom")
		(5 "F.SilkS" user "Ref Des/Silkscreen Top")
		(7 "B.SilkS" user "Ref Des/Silkscreen Bottom")
		(1 "F.Mask" user "Board Geometry/Soldermask Top")
		(3 "B.Mask" user "Board Geometry/Soldermask Bottom")
		(17 "Dwgs.User" user "User.Drawings")
		(19 "Cmts.User" user "User.Comments")
		(21 "Eco1.User" user "User.Eco1")
		(23 "Eco2.User" user "User.Eco2")
		(25 "Edge.Cuts" user "Board Geometry/Outline")
		(27 "Margin" user)
		(31 "F.CrtYd" user "Package Geometry/Place Bound Top")
		(29 "B.CrtYd" user "Package Geometry/Place Bound Bottom")
		(35 "F.Fab" user "Ref Des/Assembly Top")
		(33 "B.Fab" user "Ref Des/Assembly Bottom")
	)
	(footprint ""
		(layer "F.Cu")
		(at 158.500064 -66.699892 180)
		(property "Reference" "DIMM2"
			(at 0 0 180)
			(layer "F.SilkS")
			(hide yes)
			(effects
				(font
					(size 1.27 1.27)
				)
			)
		)
		(property "Value" "DDR3-204P-174-COLAY-1-GP"
			(at -40.682164 -17.468088 180)
			(unlocked yes)
			(layer "F.Fab")
			(hide yes)
			(effects
				(font
					(size 1.016 1.016)
					(thickness 0.1524)
				)
			)
		)
		(property "Device Type" "AS0A626-H8SN-7H-COLAY-1"
			(at -40.682164 -18.992088 180)
			(unlocked yes)
			(layer "F.Fab")
			(hide yes)
			(effects
				(font
					(size 1.016 1.016)
					(thickness 0.1524)
				)
			)
		)
		(duplicate_pad_numbers_are_jumpers no)
		(pad "154" smd custom
			(at 16.649954 -4.106672 180)
			(size 0.1143 0.1143)
			(layers "F.Cu" "F.Mask" "F.Paste")
			(net "M_A_DQS_DN5")
			(options
				(clearance outline)
				(anchor circle)
			)
			(primitives
				(gr_poly
					(pts
						(xy 0 0.9017) (xy -0.03175 0.89916) (xy -0.0635 0.889) (xy -0.09144 0.87376) (xy -0.11684 0.85344)
						(xy -0.13716 0.82804) (xy -0.1524 0.8001) (xy -0.16256 0.76835) (xy -0.1651 0.7366) (xy -0.1651 0.44958)
						(xy -0.17272 0.44196) (xy -0.19812 0.4064) (xy -0.2032 0.39624) (xy -0.20701 0.38735) (xy -0.21209 0.37719)
						(xy -0.2159 0.36703) (xy -0.21844 0.35687) (xy -0.22225 0.34544) (xy -0.22352 0.33528) (xy -0.22606 0.32512)
						(xy -0.22733 0.31369) (xy -0.22733 0.30353) (xy -0.2286 0.2921) (xy -0.22733 0.28067) (xy -0.22733 0.27051)
						(xy -0.22606 0.25908) (xy -0.22352 0.24892) (xy -0.22225 0.23876) (xy -0.21844 0.22733) (xy -0.2159 0.21717)
						(xy -0.21209 0.20701) (xy -0.20701 0.19685) (xy -0.2032 0.18796) (xy -0.19812 0.1778) (xy -0.17272 0.14224)
						(xy -0.1651 0.13462) (xy -0.1651 -0.7366) (xy -0.16256 -0.76835) (xy -0.1524 -0.8001) (xy -0.13716 -0.82804)
						(xy -0.11684 -0.85344) (xy -0.09144 -0.87376) (xy -0.0635 -0.889) (xy -0.03175 -0.89916) (xy 0 -0.9017)
						(xy 0.03175 -0.89916) (xy 0.0635 -0.889) (xy 0.09144 -0.87376) (xy 0.11684 -0.85344) (xy 0.13716 -0.82804)
						(xy 0.1524 -0.8001) (xy 0.16256 -0.76835) (xy 0.1651 -0.7366) (xy 0.1651 0.13462) (xy 0.17272 0.14224)
						(xy 0.19812 0.1778) (xy 0.2032 0.18796) (xy 0.20701 0.19685) (xy 0.21209 0.20701) (xy 0.2159 0.21717)
						(xy 0.21844 0.22733) (xy 0.22225 0.23876) (xy 0.22352 0.24892) (xy 0.22606 0.25908) (xy 0.22733 0.27051)
						(xy 0.22733 0.28067) (xy 0.2286 0.2921) (xy 0.22733 0.30353) (xy 0.22733 0.31369) (xy 0.22606 0.32512)
						(xy 0.22352 0.33528) (xy 0.22225 0.34544) (xy 0.21844 0.35687) (xy 0.2159 0.36703) (xy 0.21209 0.37719)
						(xy 0.20701 0.38735) (xy 0.2032 0.39624) (xy 0.19812 0.4064) (xy 0.17272 0.44196) (xy 0.1651 0.44958)
						(xy 0.1651 0.7366) (xy 0.16256 0.76835) (xy 0.1524 0.8001) (xy 0.13716 0.82804) (xy 0.11684 0.85344)
						(xy 0.09144 0.87376) (xy 0.0635 0.889) (xy 0.03175 0.89916)
					)
					(width 0)
					(fill yes)
				)
			)
		)
		(pad "155" smd custom
			(at 16.949928 4.106672 180)
			(size 0.1143 0.1143)
			(layers "F.Cu" "F.Mask" "F.Paste")
			(net "GND")
			(options
				(clearance outline)
				(anchor circle)
			)
			(primitives
				(gr_poly
					(pts
						(xy 0 0.9017) (xy -0.03175 0.89916) (xy -0.0635 0.889) (xy -0.09144 0.87376) (xy -0.11684 0.85344)
						(xy -0.13716 0.82804) (xy -0.1524 0.8001) (xy -0.16256 0.76835) (xy -0.1651 0.7366) (xy -0.1651 0.11938)
						(xy -0.17272 0.11176) (xy -0.19812 0.0762) (xy -0.2032 0.06604) (xy -0.20701 0.05715) (xy -0.21209 0.04699)
						(xy -0.2159 0.03683) (xy -0.21844 0.02667) (xy -0.22225 0.01524) (xy -0.22352 0.00508) (xy -0.22606 -0.00508)
						(xy -0.22733 -0.01651) (xy -0.22733 -0.02667) (xy -0.2286 -0.0381) (xy -0.22733 -0.04953) (xy -0.22733 -0.05969)
						(xy -0.22606 -0.07112) (xy -0.22352 -0.08128) (xy -0.22225 -0.09144) (xy -0.21844 -0.10287) (xy -0.2159 -0.11303)
						(xy -0.21209 -0.12319) (xy -0.20701 -0.13335) (xy -0.2032 -0.14224) (xy -0.19812 -0.1524) (xy -0.17272 -0.18796)
						(xy -0.1651 -0.19558) (xy -0.1651 -0.7366) (xy -0.16256 -0.76835) (xy -0.1524 -0.8001) (xy -0.13716 -0.82804)
						(xy -0.11684 -0.85344) (xy -0.09144 -0.87376) (xy -0.0635 -0.889) (xy -0.03175 -0.89916) (xy 0 -0.9017)
						(xy 0.03175 -0.89916) (xy 0.0635 -0.889) (xy 0.09144 -0.87376) (xy 0.11684 -0.85344) (xy 0.13716 -0.82804)
						(xy 0.1524 -0.8001) (xy 0.16256 -0.76835) (xy 0.1651 -0.7366) (xy 0.1651 -0.19685) (xy 0.17272 -0.18923)
						(xy 0.17907 -0.18034) (xy 0.18669 -0.17145) (xy 0.19177 -0.16256) (xy 0.19812 -0.15367) (xy 0.20828 -0.13335)
						(xy 0.21971 -0.10287) (xy 0.22225 -0.09271) (xy 0.22479 -0.08128) (xy 0.22606 -0.07112) (xy 0.2286 -0.05969)
						(xy 0.2286 -0.01651) (xy 0.22606 -0.00508) (xy 0.22479 0.00508) (xy 0.22225 0.01651) (xy 0.21971 0.02667)
						(xy 0.20828 0.05715) (xy 0.19812 0.07747) (xy 0.19177 0.08636) (xy 0.18669 0.09525) (xy 0.17907 0.10414)
						(xy 0.17272 0.11303) (xy 0.1651 0.12065) (xy 0.1651 0.7366) (xy 0.16256 0.76835) (xy 0.1524 0.8001)
						(xy 0.13716 0.82804) (xy 0.11684 0.85344) (xy 0.09144 0.87376) (xy 0.0635 0.889) (xy 0.03175 0.89916)
					)
					(width 0)
					(fill yes)
				)
			)
		)
		(pad "156" smd custom
			(at 17.249902 -4.106672 180)
			(size 0.1143 0.1143)
			(layers "F.Cu" "F.Mask" "F.Paste")
			(net "M_A_DQS_DP5")
			(options
				(clearance outline)
				(anchor circle)
			)
			(primitives
				(gr_poly
					(pts
						(xy 0 0.9017) (xy -0.03175 0.89916) (xy -0.0635 0.889) (xy -0.09144 0.87376) (xy -0.11684 0.85344)
						(xy -0.13716 0.82804) (xy -0.1524 0.8001) (xy -0.16256 0.76835) (xy -0.1651 0.7366) (xy -0.1651 0.19685)
						(xy -0.17272 0.18923) (xy -0.17907 0.18034) (xy -0.18669 0.17145) (xy -0.19177 0.16256) (xy -0.19812 0.15367)
						(xy -0.20828 0.13335) (xy -0.21971 0.10287) (xy -0.22225 0.09271) (xy -0.22479 0.08128) (xy -0.22606 0.07112)
						(xy -0.2286 0.05969) (xy -0.2286 0.01651) (xy -0.22606 0.00508) (xy -0.22479 -0.00508) (xy -0.22225 -0.01651)
						(xy -0.21971 -0.02667) (xy -0.20828 -0.05715) (xy -0.19812 -0.07747) (xy -0.19177 -0.08636) (xy -0.18669 -0.09525)
						(xy -0.17907 -0.10414) (xy -0.17272 -0.11303) (xy -0.1651 -0.12065) (xy -0.1651 -0.7366) (xy -0.16256 -0.76835)
						(xy -0.1524 -0.8001) (xy -0.13716 -0.82804) (xy -0.11684 -0.85344) (xy -0.09144 -0.87376) (xy -0.0635 -0.889)
						(xy -0.03175 -0.89916) (xy 0 -0.9017) (xy 0.03175 -0.89916) (xy 0.0635 -0.889) (xy 0.09144 -0.87376)
						(xy 0.11684 -0.85344) (xy 0.13716 -0.82804) (xy 0.1524 -0.8001) (xy 0.16256 -0.76835) (xy 0.1651 -0.7366)
						(xy 0.1651 -0.11938) (xy 0.17272 -0.11176) (xy 0.19812 -0.0762) (xy 0.2032 -0.06604) (xy 0.20701 -0.05715)
						(xy 0.21209 -0.04699) (xy 0.2159 -0.03683) (xy 0.21844 -0.02667) (xy 0.22225 -0.01524) (xy 0.22352 -0.00508)
						(xy 0.22606 0.00508) (xy 0.22733 0.01651) (xy 0.22733 0.02667) (xy 0.2286 0.0381) (xy 0.22733 0.04953)
						(xy 0.22733 0.05969) (xy 0.22606 0.07112) (xy 0.22352 0.08128) (xy 0.22225 0.09144) (xy 0.21844 0.10287)
						(xy 0.2159 0.11303) (xy 0.21209 0.12319) (xy 0.20701 0.13335) (xy 0.2032 0.14224) (xy 0.19812 0.1524)
						(xy 0.17272 0.18796) (xy 0.1651 0.19558) (xy 0.1651 0.7366) (xy 0.16256 0.76835) (xy 0.1524 0.8001)
						(xy 0.13716 0.82804) (xy 0.11684 0.85344) (xy 0.09144 0.87376) (xy 0.0635 0.889) (xy 0.03175 0.89916)
					)
					(width 0)
					(fill yes)
				)
			)
		)
		(pad "157" smd custom
			(at 17.549876 4.106672 180)
			(size 0.1143 0.1143)
			(layers "F.Cu" "F.Mask" "F.Paste")
			(net "GND")
			(options
				(clearance outline)
				(anchor circle)
			)
			(primitives
				(gr_poly
					(pts
						(xy 0 0.9017) (xy -0.03175 0.89916) (xy -0.0635 0.889) (xy -0.09144 0.87376) (xy -0.11684 0.85344)
						(xy -0.13716 0.82804) (xy -0.1524 0.8001) (xy -0.16256 0.76835) (xy -0.1651 0.7366) (xy -0.1651 -0.13462)
						(xy -0.17272 -0.14224) (xy -0.19812 -0.1778) (xy -0.2032 -0.18796) (xy -0.20701 -0.19685) (xy -0.21209 -0.20701)
						(xy -0.2159 -0.21717) (xy -0.21844 -0.22733) (xy -0.22225 -0.23876) (xy -0.22352 -0.24892) (xy -0.22606 -0.25908)
						(xy -0.22733 -0.27051) (xy -0.22733 -0.28067) (xy -0.2286 -0.2921) (xy -0.22733 -0.30353) (xy -0.22733 -0.31369)
						(xy -0.22606 -0.32512) (xy -0.22352 -0.33528) (xy -0.22225 -0.34544) (xy -0.21844 -0.35687) (xy -0.2159 -0.36703)
						(xy -0.21209 -0.37719) (xy -0.20701 -0.38735) (xy -0.2032 -0.39624) (xy -0.19812 -0.4064) (xy -0.17272 -0.44196)
						(xy -0.1651 -0.44958) (xy -0.1651 -0.7366) (xy -0.16256 -0.76835) (xy -0.1524 -0.8001) (xy -0.13716 -0.82804)
						(xy -0.11684 -0.85344) (xy -0.09144 -0.87376) (xy -0.0635 -0.889) (xy -0.03175 -0.89916) (xy 0 -0.9017)
						(xy 0.03175 -0.89916) (xy 0.0635 -0.889) (xy 0.09144 -0.87376) (xy 0.11684 -0.85344) (xy 0.13716 -0.82804)
						(xy 0.1524 -0.8001) (xy 0.16256 -0.76835) (xy 0.1651 -0.7366) (xy 0.1651 -0.44958) (xy 0.17272 -0.44196)
						(xy 0.19812 -0.4064) (xy 0.2032 -0.39624) (xy 0.20701 -0.38735) (xy 0.21209 -0.37719) (xy 0.2159 -0.36703)
						(xy 0.21844 -0.35687) (xy 0.22225 -0.34544) (xy 0.22352 -0.33528) (xy 0.22606 -0.32512) (xy 0.22733 -0.31369)
						(xy 0.22733 -0.30353) (xy 0.2286 -0.2921) (xy 0.22733 -0.28067) (xy 0.22733 -0.27051) (xy 0.22606 -0.25908)
						(xy 0.22352 -0.24892) (xy 0.22225 -0.23876) (xy 0.21844 -0.22733) (xy 0.2159 -0.21717) (xy 0.21209 -0.20701)
						(xy 0.20701 -0.19685) (xy 0.2032 -0.18796) (xy 0.19812 -0.1778) (xy 0.17272 -0.14224) (xy 0.1651 -0.13462)
						(xy 0.1651 0.7366) (xy 0.16256 0.76835) (xy 0.1524 0.8001) (xy 0.13716 0.82804) (xy 0.11684 0.85344)
						(xy 0.09144 0.87376) (xy 0.0635 0.889) (xy 0.03175 0.89916)
					)
					(width 0)
					(fill yes)
				)
			)
		)
		(pad "158" smd custom
			(at 17.850104 -4.106672 180)
			(size 0.1143 0.1143)
			(layers "F.Cu" "F.Mask" "F.Paste")
			(net "GND")
			(options
				(clearance outline)
				(anchor circle)
			)
			(primitives
				(gr_poly
					(pts
						(xy 0 0.9017) (xy -0.03175 0.89916) (xy -0.0635 0.889) (xy -0.09144 0.87376) (xy -0.11684 0.85344)
						(xy -0.13716 0.82804) (xy -0.1524 0.8001) (xy -0.16256 0.76835) (xy -0.1651 0.7366) (xy -0.1651 0.44958)
						(xy -0.17272 0.44196) (xy -0.19812 0.4064) (xy -0.2032 0.39624) (xy -0.20701 0.38735) (xy -0.21209 0.37719)
						(xy -0.2159 0.36703) (xy -0.21844 0.35687) (xy -0.22225 0.34544) (xy -0.22352 0.33528) (xy -0.22606 0.32512)
						(xy -0.22733 0.31369) (xy -0.22733 0.30353) (xy -0.2286 0.2921) (xy -0.22733 0.28067) (xy -0.22733 0.27051)
						(xy -0.22606 0.25908) (xy -0.22352 0.24892) (xy -0.22225 0.23876) (xy -0.21844 0.22733) (xy -0.2159 0.21717)
						(xy -0.21209 0.20701) (xy -0.20701 0.19685) (xy -0.2032 0.18796) (xy -0.19812 0.1778) (xy -0.17272 0.14224)
						(xy -0.1651 0.13462) (xy -0.1651 -0.7366) (xy -0.16256 -0.76835) (xy -0.1524 -0.8001) (xy -0.13716 -0.82804)
						(xy -0.11684 -0.85344) (xy -0.09144 -0.87376) (xy -0.0635 -0.889) (xy -0.03175 -0.89916) (xy 0 -0.9017)
						(xy 0.03175 -0.89916) (xy 0.0635 -0.889) (xy 0.09144 -0.87376) (xy 0.11684 -0.85344) (xy 0.13716 -0.82804)
						(xy 0.1524 -0.8001) (xy 0.16256 -0.76835) (xy 0.1651 -0.7366) (xy 0.1651 0.13462) (xy 0.17272 0.14224)
						(xy 0.19812 0.1778) (xy 0.2032 0.18796) (xy 0.20701 0.19685) (xy 0.21209 0.20701) (xy 0.2159 0.21717)
						(xy 0.21844 0.22733) (xy 0.22225 0.23876) (xy 0.22352 0.24892) (xy 0.22606 0.25908) (xy 0.22733 0.27051)
						(xy 0.22733 0.28067) (xy 0.2286 0.2921) (xy 0.22733 0.30353) (xy 0.22733 0.31369) (xy 0.22606 0.32512)
						(xy 0.22352 0.33528) (xy 0.22225 0.34544) (xy 0.21844 0.35687) (xy 0.2159 0.36703) (xy 0.21209 0.37719)
						(xy 0.20701 0.38735) (xy 0.2032 0.39624) (xy 0.19812 0.4064) (xy 0.17272 0.44196) (xy 0.1651 0.44958)
						(xy 0.1651 0.7366) (xy 0.16256 0.76835) (xy 0.1524 0.8001) (xy 0.13716 0.82804) (xy 0.11684 0.85344)
						(xy 0.09144 0.87376) (xy 0.0635 0.889) (xy 0.03175 0.89916)
					)
					(width 0)
					(fill yes)
				)
			)
		)
		(pad "159" smd custom
			(at 18.150078 4.106672 180)
			(size 0.1143 0.1143)
			(layers "F.Cu" "F.Mask" "F.Paste")
			(net "M_A_DQ46")
			(options
				(clearance outline)
				(anchor circle)
			)
			(primitives
				(gr_poly
					(pts
						(xy 0 0.9017) (xy -0.03175 0.89916) (xy -0.0635 0.889) (xy -0.09144 0.87376) (xy -0.11684 0.85344)
						(xy -0.13716 0.82804) (xy -0.1524 0.8001) (xy -0.16256 0.76835) (xy -0.1651 0.7366) (xy -0.1651 0.11938)
						(xy -0.17272 0.11176) (xy -0.19812 0.0762) (xy -0.2032 0.06604) (xy -0.20701 0.05715) (xy -0.21209 0.04699)
						(xy -0.2159 0.03683) (xy -0.21844 0.02667) (xy -0.22225 0.01524) (xy -0.22352 0.00508) (xy -0.22606 -0.00508)
						(xy -0.22733 -0.01651) (xy -0.22733 -0.02667) (xy -0.2286 -0.0381) (xy -0.22733 -0.04953) (xy -0.22733 -0.05969)
						(xy -0.22606 -0.07112) (xy -0.22352 -0.08128) (xy -0.22225 -0.09144) (xy -0.21844 -0.10287) (xy -0.2159 -0.11303)
						(xy -0.21209 -0.12319) (xy -0.20701 -0.13335) (xy -0.2032 -0.14224) (xy -0.19812 -0.1524) (xy -0.17272 -0.18796)
						(xy -0.1651 -0.19558) (xy -0.1651 -0.7366) (xy -0.16256 -0.76835) (xy -0.1524 -0.8001) (xy -0.13716 -0.82804)
						(xy -0.11684 -0.85344) (xy -0.09144 -0.87376) (xy -0.0635 -0.889) (xy -0.03175 -0.89916) (xy 0 -0.9017)
						(xy 0.03175 -0.89916) (xy 0.0635 -0.889) (xy 0.09144 -0.87376) (xy 0.11684 -0.85344) (xy 0.13716 -0.82804)
						(xy 0.1524 -0.8001) (xy 0.16256 -0.76835) (xy 0.1651 -0.7366) (xy 0.1651 -0.19685) (xy 0.17272 -0.18923)
						(xy 0.17907 -0.18034) (xy 0.18669 -0.17145) (xy 0.19177 -0.16256) (xy 0.19812 -0.15367) (xy 0.20828 -0.13335)
						(xy 0.21971 -0.10287) (xy 0.22225 -0.09271) (xy 0.22479 -0.08128) (xy 0.22606 -0.07112) (xy 0.2286 -0.05969)
						(xy 0.2286 -0.01651) (xy 0.22606 -0.00508) (xy 0.22479 0.00508) (xy 0.22225 0.01651) (xy 0.21971 0.02667)
						(xy 0.20828 0.05715) (xy 0.19812 0.07747) (xy 0.19177 0.08636) (xy 0.18669 0.09525) (xy 0.17907 0.10414)
						(xy 0.17272 0.11303) (xy 0.1651 0.12065) (xy 0.1651 0.7366) (xy 0.16256 0.76835) (xy 0.1524 0.8001)
						(xy 0.13716 0.82804) (xy 0.11684 0.85344) (xy 0.09144 0.87376) (xy 0.0635 0.889) (xy 0.03175 0.89916)
					)
					(width 0)
					(fill yes)
				)
			)
		)
		(pad "160" smd custom
			(at 18.450052 -4.106672 180)
			(size 0.1143 0.1143)
			(layers "F.Cu" "F.Mask" "F.Paste")
			(net "M_A_DQ42")
			(options
				(clearance outline)
				(anchor circle)
			)
			(primitives
				(gr_poly
					(pts
						(xy 0 0.9017) (xy -0.03175 0.89916) (xy -0.0635 0.889) (xy -0.09144 0.87376) (xy -0.11684 0.85344)
						(xy -0.13716 0.82804) (xy -0.1524 0.8001) (xy -0.16256 0.76835) (xy -0.1651 0.7366) (xy -0.1651 0.19685)
						(xy -0.17272 0.18923) (xy -0.17907 0.18034) (xy -0.18669 0.17145) (xy -0.19177 0.16256) (xy -0.19812 0.15367)
						(xy -0.20828 0.13335) (xy -0.21971 0.10287) (xy -0.22225 0.09271) (xy -0.22479 0.08128) (xy -0.22606 0.07112)
						(xy -0.2286 0.05969) (xy -0.2286 0.01651) (xy -0.22606 0.00508) (xy -0.22479 -0.00508) (xy -0.22225 -0.01651)
						(xy -0.21971 -0.02667) (xy -0.20828 -0.05715) (xy -0.19812 -0.07747) (xy -0.19177 -0.08636) (xy -0.18669 -0.09525)
						(xy -0.17907 -0.10414) (xy -0.17272 -0.11303) (xy -0.1651 -0.12065) (xy -0.1651 -0.7366) (xy -0.16256 -0.76835)
						(xy -0.1524 -0.8001) (xy -0.13716 -0.82804) (xy -0.11684 -0.85344) (xy -0.09144 -0.87376) (xy -0.0635 -0.889)
						(xy -0.03175 -0.89916) (xy 0 -0.9017) (xy 0.03175 -0.89916) (xy 0.0635 -0.889) (xy 0.09144 -0.87376)
						(xy 0.11684 -0.85344) (xy 0.13716 -0.82804) (xy 0.1524 -0.8001) (xy 0.16256 -0.76835) (xy 0.1651 -0.7366)
						(xy 0.1651 -0.11938) (xy 0.17272 -0.11176) (xy 0.19812 -0.0762) (xy 0.2032 -0.06604) (xy 0.20701 -0.05715)
						(xy 0.21209 -0.04699) (xy 0.2159 -0.03683) (xy 0.21844 -0.02667) (xy 0.22225 -0.01524) (xy 0.22352 -0.00508)
						(xy 0.22606 0.00508) (xy 0.22733 0.01651) (xy 0.22733 0.02667) (xy 0.2286 0.0381) (xy 0.22733 0.04953)
						(xy 0.22733 0.05969) (xy 0.22606 0.07112) (xy 0.22352 0.08128) (xy 0.22225 0.09144) (xy 0.21844 0.10287)
						(xy 0.2159 0.11303) (xy 0.21209 0.12319) (xy 0.20701 0.13335) (xy 0.2032 0.14224) (xy 0.19812 0.1524)
						(xy 0.17272 0.18796) (xy 0.1651 0.19558) (xy 0.1651 0.7366) (xy 0.16256 0.76835) (xy 0.1524 0.8001)
						(xy 0.13716 0.82804) (xy 0.11684 0.85344) (xy 0.09144 0.87376) (xy 0.0635 0.889) (xy 0.03175 0.89916)
					)
					(width 0)
					(fill yes)
				)
			)
		)
	)
)
